# T6G (Grand Teton) — schematic netlist excerpt (pin names and nets, part order shuffled) for the footprints in the layout excerpt that follows; sources: Cadence DE-HDL packaged netlist, KiCad conversion of 04192023_DAF0TMB3IC0_F0TG_MB_C_brd_V02_OCP.brd

J37  SCONN288_DDR506112002KQ  IO  pkg DDR288S_1-1VXC  page 109
  VIN_BULK0  = P12V_MEM_CPU1
  RFU0  = NC
  VIN_MGMT  = P3V3_AUX
  HSCL  = I3C_SPD_DDRL_CPU1_SCL
  HSDA  = I3C_SPD_DDRL_CPU1_SDA
  VSS0  = GND
  DQ0_A  = M_L_CPU1_SA_DQ<0>
  VSS1  = GND
  DQ1_A  = M_L_CPU1_SA_DQ<1>
  VSS2  = GND
  DQS0_A_T  = M_L_CPU1_SA_DQS_DP<0>
  DQS0_A_C  = M_L_CPU1_SA_DQS_DN<0>
  VSS3  = GND
  DQ4_A  = M_L_CPU1_SA_DQ<4>
  VSS4  = GND
  DQ5_A  = M_L_CPU1_SA_DQ<5>
  VSS5  = GND
  DQ8_A  = M_L_CPU1_SA_DQ<8>
  VSS6  = GND
  DQ9_A  = M_L_CPU1_SA_DQ<9>
  VSS7  = GND
  DQS1_A_T  = M_L_CPU1_SA_DQS_DP<1>
  DQS1_A_C  = M_L_CPU1_SA_DQS_DN<1>
  VSS8  = GND
  DQ12_A  = M_L_CPU1_SA_DQ<12>
  VSS9  = GND
  DQ13_A  = M_L_CPU1_SA_DQ<13>
  VSS10  = GND
  DQ16_A  = M_L_CPU1_SA_DQ<16>
  VSS11  = GND
  DQ17_A  = M_L_CPU1_SA_DQ<17>
  VSS12  = GND
  DQS2_A_T  = M_L_CPU1_SA_DQS_DP<2>
  DQS2_A_C  = M_L_CPU1_SA_DQS_DN<2>
  VSS13  = GND
  DQ20_A  = M_L_CPU1_SA_DQ<20>
  VSS14  = GND
  DQ21_A  = M_L_CPU1_SA_DQ<21>
  VSS15  = GND
  DQ24_A  = M_L_CPU1_SA_DQ<24>
  VSS16  = GND
  DQ25_A  = M_L_CPU1_SA_DQ<25>
  VSS17  = GND
  DQS3_A_T  = M_L_CPU1_SA_DQS_DP<3>
  DQS3_A_C  = M_L_CPU1_SA_DQS_DN<3>
  VSS18  = GND
  DQ28_A  = M_L_CPU1_SA_DQ<28>
  VSS19  = GND
  DQ29_A  = M_L_CPU1_SA_DQ<29>
  VSS20  = GND
  CB0_A  = M_L_CPU1_SA_CB<0>
  VSS21  = GND
  CB1_A  = M_L_CPU1_SA_CB<1>
  VSS22  = GND
  DQS4_A_T  = M_L_CPU1_SA_DQS_DP<4>
  DQS4_A_C  = M_L_CPU1_SA_DQS_DN<4>
  VSS23  = GND
  CB4_A  = M_L_CPU1_SA_CB<4>
  VSS24  = GND
  CB5_A  = M_L_CPU1_SA_CB<5>
  VSS25  = GND
  ALERT_N  = M_L_CPU1_ALERT_N
  VSS26  = GND
  CS0_A_N  = M_L_CPU1_SA_CS_N<0>
  VSS27  = GND
  CA0_A  = M_L_CPU1_SA_CA<0>
  VSS28  = GND
  CA2_A  = M_L_CPU1_SA_CA<2>
  VSS29  = GND
  CA4_A  = M_L_CPU1_SA_CA<4>
  VSS30  = GND
  CA6_A  = M_L_CPU1_SA_CA<6>
  VSS31  = GND
  PAR_A  = M_L_CPU1_SA_PAR
  VSS32  = GND
  CA0_B  = M_L_CPU1_SB_CA<0>
  VSS33  = GND
  CA2_B  = M_L_CPU1_SB_CA<2>
  VSS34  = GND
  CA4_B  = M_L_CPU1_SB_CA<4>
  VSS35  = GND
  CA6_B  = M_L_CPU1_SB_CA<6>
  VSS36  = GND
  CS0_B_N  = M_L_CPU1_SB_CS_N<0>
  VSS37  = GND
  \lbd||rsp_a_n\  = M_L_CPU1_SA_RSP<0>
  \lbs||rsp_b_n\  = M_L_CPU1_SB_RSP<0>
  VSS38  = GND
  CB4_B  = M_L_CPU1_SB_CB<4>
  VSS39  = GND
  CB5_B  = M_L_CPU1_SB_CB<5>
  VSS40  = GND
  \dqs9_b_t||tdqs9_b_t||dbi4_b_n\  = M_L_CPU1_SB_DQS_DP<9>
  \dqs9_b_c||tdqs9_b_c\  = M_L_CPU1_SB_DQS_DN<9>
  VSS41  = GND
  CB0_B  = M_L_CPU1_SB_CB<0>
  VSS42  = GND
  CB1_B  = M_L_CPU1_SB_CB<1>
  VSS43  = GND
  DQ0_B  = M_L_CPU1_SB_DQ<0>
  VSS44  = GND
  DQ1_B  = M_L_CPU1_SB_DQ<1>
  VSS45  = GND
  DQS0_B_T  = M_L_CPU1_SB_DQS_DP<0>
  DQS0_B_C  = M_L_CPU1_SB_DQS_DN<0>
  VSS46  = GND
  DQ4_B  = M_L_CPU1_SB_DQ<4>
  VSS47  = GND
  DQ5_B  = M_L_CPU1_SB_DQ<5>
  VSS48  = GND
  DQ8_B  = M_L_CPU1_SB_DQ<8>
  VSS49  = GND
  DQ9_B  = M_L_CPU1_SB_DQ<9>
  VSS50  = GND
  DQS1_B_T  = M_L_CPU1_SB_DQS_DP<1>
  DQS1_B_C  = M_L_CPU1_SB_DQS_DN<1>
  VSS51  = GND
  DQ12_B  = M_L_CPU1_SB_DQ<12>
  VSS52  = GND
  DQ13_B  = M_L_CPU1_SB_DQ<13>
  VSS53  = GND
  DQ16_B  = M_L_CPU1_SB_DQ<16>
  VSS54  = GND
  DQ17_B  = M_L_CPU1_SB_DQ<17>
  VSS55  = GND
  DQS2_B_T  = M_L_CPU1_SB_DQS_DP<2>
  DQS2_B_C  = M_L_CPU1_SB_DQS_DN<2>
  VSS56  = GND
  DQ20_B  = M_L_CPU1_SB_DQ<20>
  VSS57  = GND
  DQ21_B  = M_L_CPU1_SB_DQ<21>
  VSS58  = GND
  DQ24_B  = M_L_CPU1_SB_DQ<24>
  VSS59  = GND
  DQ25_B  = M_L_CPU1_SB_DQ<25>
  VSS60  = GND
  DQS3_B_T  = M_L_CPU1_SB_DQS_DP<3>
  DQS3_B_C  = M_L_CPU1_SB_DQS_DN<3>
  VSS61  = GND
  DQ28_B  = M_L_CPU1_SB_DQ<28>
  VSS62  = GND
  DQ29_B  = M_L_CPU1_SB_DQ<29>
  VSS63  = GND
  RFU1  = NC
  VIN_BULK1  = P12V_MEM_CPU1
  VIN_BULK2  = P12V_MEM_CPU1
  \pwr_good||fail_n\  = PWRGD_CHL_CPU1_DIMM
  HAS  = PD_CHL_CPU1_DIMM_SAA
  RFU2  = NC
  RFU3  = NC
  VSS64  = GND
  DQ2_A  = M_L_CPU1_SA_DQ<2>
  VSS65  = GND
  DQ3_A  = M_L_CPU1_SA_DQ<3>
  VSS66  = GND
  \dqs5_a_c||tdqs5_a_c||dqs5_a_t||tdqs5_a_t\  = M_L_CPU1_SA_DQS_DN<5>
  \dqs5_a_t||tdqs5_a_t\  = M_L_CPU1_SA_DQS_DP<5>
  VSS67  = GND
  DQ6_A  = M_L_CPU1_SA_DQ<6>
  VSS68  = GND
  DQ7_A  = M_L_CPU1_SA_DQ<7>
  VSS69  = GND
  DQ10_A  = M_L_CPU1_SA_DQ<10>
  VSS70  = GND
  DQ11_A  = M_L_CPU1_SA_DQ<11>
  VSS71  = GND
  \dqs6_a_c||tdqs6_a_c||dqs6_a_t||tdqs6_a_t\  = M_L_CPU1_SA_DQS_DN<6>
  \dqs6_a_t||tdqs6_a_t\  = M_L_CPU1_SA_DQS_DP<6>
  VSS72  = GND
  DQ14_A  = M_L_CPU1_SA_DQ<14>
  VSS73  = GND
  DQ15_A  = M_L_CPU1_SA_DQ<15>
  VSS74  = GND
  DQ18_A  = M_L_CPU1_SA_DQ<18>
  VSS75  = GND
  DQ19_A  = M_L_CPU1_SA_DQ<19>
  VSS76  = GND
  \dqs7_a_c||tdqs7_a_c\  = M_L_CPU1_SA_DQS_DN<7>
  \dqs7_a_t||tdqs7_a_t\  = M_L_CPU1_SA_DQS_DP<7>
  VSS77  = GND
  DQ22_A  = M_L_CPU1_SA_DQ<22>
  VSS78  = GND
  DQ23_A  = M_L_CPU1_SA_DQ<23>
  VSS79  = GND
  DQ26_A  = M_L_CPU1_SA_DQ<26>
  VSS80  = GND
  DQ27_A  = M_L_CPU1_SA_DQ<27>
  VSS81  = GND
  \dqs8_a_c||tdqs8_a_c\  = M_L_CPU1_SA_DQS_DN<8>
  \dqs8_a_t||tdqs8_a_t\  = M_L_CPU1_SA_DQS_DP<8>
  VSS82  = GND
  DQ30_A  = M_L_CPU1_SA_DQ<30>
  VSS83  = GND
  DQ31_A  = M_L_CPU1_SA_DQ<31>
  VSS84  = GND
  CB2_A  = M_L_CPU1_SA_CB<2>
  VSS85  = GND
  CB3_A  = M_L_CPU1_SA_CB<3>
  VSS86  = GND
  \dqs9_a_c||tdqs9_a_c\  = M_L_CPU1_SA_DQS_DN<9>
  \dqs9_a_t||tdqs9_a_t\  = M_L_CPU1_SA_DQS_DP<9>
  VSS87  = GND
  CB6_A  = M_L_CPU1_SA_CB<6>
  VSS88  = GND
  CB7_A  = M_L_CPU1_SA_CB<7>
  VSS89  = GND
  RESET_N  = M_L_CPU1_RESET_N
  VSS90  = GND
  CS1_A_N  = M_L_CPU1_SA_CS_N<1>
  VSS91  = GND
  CA1_A  = M_L_CPU1_SA_CA<1>
  VSS92  = GND
  CA3_A  = M_L_CPU1_SA_CA<3>
  VSS93  = GND
  CA5_A  = M_L_CPU1_SA_CA<5>
  VSS94  = GND
  CK_T  = M_L_CPU1_CLK_DP<0>
  CK_C  = M_L_CPU1_CLK_DN<0>
  VSS95  = GND
  RFU4  = NC
  CA1_B  = M_L_CPU1_SB_CA<1>
  VSS96  = GND
  CA3_B  = M_L_CPU1_SB_CA<3>
  VSS97  = GND
  CA5_B  = M_L_CPU1_SB_CA<5>
  VSS98  = GND
  PAR_B  = M_L_CPU1_SB_PAR
  VSS99  = GND
  CS1_B_N  = M_L_CPU1_SB_CS_N<1>
  VSS100  = GND
  RFU5  = NC
  RFU6  = NC
  VSS101  = GND
  CB6_B  = M_L_CPU1_SB_CB<6>
  VSS102  = GND
  CB7_B  = M_L_CPU1_SB_CB<7>
  VSS103  = GND
  DQS4_B_C  = M_L_CPU1_SB_DQS_DN<4>
  DQS4_B_T  = M_L_CPU1_SB_DQS_DP<4>
  VSS104  = GND
  CB2_B  = M_L_CPU1_SB_CB<2>
  VSS105  = GND
  CB3_B  = M_L_CPU1_SB_CB<3>
  VSS106  = GND
  DQ2_B  = M_L_CPU1_SB_DQ<2>
  VSS107  = GND
  DQ3_B  = M_L_CPU1_SB_DQ<3>
  VSS108  = GND
  \dqs5_b_c||tdqs5_b_c\  = M_L_CPU1_SB_DQS_DN<5>
  \dqs5_b_t||tdqs5_b_t\  = M_L_CPU1_SB_DQS_DP<5>
  VSS109  = GND
  DQ6_B  = M_L_CPU1_SB_DQ<6>
  VSS110  = GND
  DQ7_B  = M_L_CPU1_SB_DQ<7>
  VSS111  = GND
  DQ10_B  = M_L_CPU1_SB_DQ<10>
  VSS112  = GND
  DQ11_B  = M_L_CPU1_SB_DQ<11>
  VSS113  = GND
  \dqs6_b_c||tdqs6_b_c\  = M_L_CPU1_SB_DQS_DN<6>
  \dqs6_b_t||tdqs6_b_t\  = M_L_CPU1_SB_DQS_DP<6>
  VSS114  = GND
  DQ14_B  = M_L_CPU1_SB_DQ<14>
  VSS115  = GND
  DQ15_B  = M_L_CPU1_SB_DQ<15>
  VSS116  = GND
  DQ18_B  = M_L_CPU1_SB_DQ<18>
  VSS117  = GND
  DQ19_B  = M_L_CPU1_SB_DQ<19>
  VSS118  = GND
  \dqs7_b_c||tdqs7_b_c\  = M_L_CPU1_SB_DQS_DN<7>
  \dqs7_b_t||tdqs7_b_t\  = M_L_CPU1_SB_DQS_DP<7>
  VSS119  = GND
  DQ22_B  = M_L_CPU1_SB_DQ<22>
  VSS120  = GND
  DQ23_B  = M_L_CPU1_SB_DQ<23>
  VSS121  = GND
  DQ26_B  = M_L_CPU1_SB_DQ<26>
  VSS122  = GND
  DQ27_B  = M_L_CPU1_SB_DQ<27>
  VSS123  = GND
  \dqs8_b_c||tdqs8_b_c\  = M_L_CPU1_SB_DQS_DN<8>
  \dqs8_b_t||tdqs8_b_t\  = M_L_CPU1_SB_DQS_DP<8>
  VSS124  = GND
  DQ30_B  = M_L_CPU1_SB_DQ<30>
  VSS125  = GND
  DQ31_B  = M_L_CPU1_SB_DQ<31>
  VSS126  = GND
  G1  = GND
  G2  = GND
  G3  = GND

(kicad_pcb
	(version 20260206)
	(generator "pcbnew")
	(generator_version "10.0")
	(general
		(thickness 1.6)
		(legacy_teardrops no)
	)
	(paper "A4")
	(title_block
		(title "04192023_DAF0TMB3IC0_F0TG_MB_C_brd_V02_OCP.brd")
		(comment 1 "Grand Teton / footprint 34 of 8354 (J37), pads 1-46 of 291")
	)
	(layers
		(0 "F.Cu" signal "TOP")
		(4 "In1.Cu" signal "GND")
		(6 "In2.Cu" signal "IN1")
		(8 "In3.Cu" signal "GND1")
		(10 "In4.Cu" signal "IN2")
		(12 "In5.Cu" signal "GND2")
		(14 "In6.Cu" signal "IN3")
		(16 "In7.Cu" signal "GND3")
		(18 "In8.Cu" signal "VCC")
		(20 "In9.Cu" signal "VCC1")
		(22 "In10.Cu" signal "GND4")
		(24 "In11.Cu" signal "IN4")
		(26 "In12.Cu" signal "GND5")
		(28 "In13.Cu" signal "IN5")
		(30 "In14.Cu" signal "GND6")
		(32 "In15.Cu" signal "IN6")
		(34 "In16.Cu" signal "GND7")
		(2 "B.Cu" signal "BOTTOM")
		(9 "F.Adhes" user "F.Adhesive")
		(11 "B.Adhes" user "B.Adhesive")
		(13 "F.Paste" user "Package Geometry/Pastemask Top")
		(15 "B.Paste" user "Package Geometry/Pastemask Bottom")
		(5 "F.SilkS" user "Ref Des/Silkscreen Top")
		(7 "B.SilkS" user "Ref Des/Silkscreen Bottom")
		(1 "F.Mask" user "Board Geometry/Soldermask Top")
		(3 "B.Mask" user "Board Geometry/Soldermask Bottom")
		(17 "Dwgs.User" user "User.Drawings")
		(19 "Cmts.User" user "User.Comments")
		(21 "Eco1.User" user "User.Eco1")
		(23 "Eco2.User" user "User.Eco2")
		(25 "Edge.Cuts" user "Board Geometry/Outline")
		(27 "Margin" user)
		(31 "F.CrtYd" user "Package Geometry/Place Bound Top")
		(29 "B.CrtYd" user "Package Geometry/Place Bound Bottom")
		(35 "F.Fab" user "Ref Des/Assembly Top")
		(33 "B.Fab" user "Ref Des/Assembly Bottom")
	)
	(footprint ""
		(layer "F.Cu")
		(at 204.197966 -255.560322 180)
		(property "Reference" "J37"
			(at 2.8702 -81.730088 0)
			(unlocked yes)
			(layer "F.SilkS")
			(effects
				(font
					(size 0.7874 0.5842)
					(thickness 0.1524)
				)
			)
		)
		(property "Value" ""
			(at 0 0 180)
			(layer "F.Fab")
			(effects
				(font
					(size 1.27 1.27)
				)
			)
		)
		(duplicate_pad_numbers_are_jumpers no)
		(pad "1" smd rect
			(at -2.050034 -63.324994 90)
			(size 0.519938 1.4986)
			(layers "F.Cu" "F.Mask" "F.Paste")
			(net "P12V_MEM_CPU1")
		)
		(pad "2" smd rect
			(at -2.050034 -62.47511 90)
			(size 0.519938 1.4986)
			(layers "F.Cu" "F.Mask" "F.Paste")
			(net "Net_2410")
		)
		(pad "3" smd rect
			(at -2.050034 -61.624972 90)
			(size 0.519938 1.4986)
			(layers "F.Cu" "F.Mask" "F.Paste")
			(net "P3V3_AUX")
		)
		(pad "4" smd rect
			(at -2.050034 -60.775088 90)
			(size 0.519938 1.4986)
			(layers "F.Cu" "F.Mask" "F.Paste")
			(net "I3C_SPD_DDRL_CPU1_SCL")
		)
		(pad "5" smd rect
			(at -2.050034 -59.92495 90)
			(size 0.519938 1.4986)
			(layers "F.Cu" "F.Mask" "F.Paste")
			(net "I3C_SPD_DDRL_CPU1_SDA")
		)
		(pad "6" smd rect
			(at -2.050034 -59.075066 90)
			(size 0.519938 1.4986)
			(layers "F.Cu" "F.Mask" "F.Paste")
			(net "GND")
		)
		(pad "7" smd rect
			(at -2.050034 -58.224928 90)
			(size 0.519938 1.4986)
			(layers "F.Cu" "F.Mask" "F.Paste")
			(net "M_L_CPU1_SA_DQ<0>")
		)
		(pad "8" smd rect
			(at -2.050034 -57.375044 90)
			(size 0.519938 1.4986)
			(layers "F.Cu" "F.Mask" "F.Paste")
			(net "GND")
		)
		(pad "9" smd rect
			(at -2.050034 -56.524906 90)
			(size 0.519938 1.4986)
			(layers "F.Cu" "F.Mask" "F.Paste")
			(net "M_L_CPU1_SA_DQ<1>")
		)
		(pad "10" smd rect
			(at -2.050034 -55.675022 90)
			(size 0.519938 1.4986)
			(layers "F.Cu" "F.Mask" "F.Paste")
			(net "GND")
		)
		(pad "11" smd rect
			(at -2.050034 -54.824884 90)
			(size 0.519938 1.4986)
			(layers "F.Cu" "F.Mask" "F.Paste")
			(net "M_L_CPU1_SA_DQS_DP<0>")
		)
		(pad "12" smd rect
			(at -2.050034 -53.975 90)
			(size 0.519938 1.4986)
			(layers "F.Cu" "F.Mask" "F.Paste")
			(net "M_L_CPU1_SA_DQS_DN<0>")
		)
		(pad "13" smd rect
			(at -2.050034 -53.125116 90)
			(size 0.519938 1.4986)
			(layers "F.Cu" "F.Mask" "F.Paste")
			(net "GND")
		)
		(pad "14" smd rect
			(at -2.050034 -52.274978 90)
			(size 0.519938 1.4986)
			(layers "F.Cu" "F.Mask" "F.Paste")
			(net "M_L_CPU1_SA_DQ<4>")
		)
		(pad "15" smd rect
			(at -2.050034 -51.425094 90)
			(size 0.519938 1.4986)
			(layers "F.Cu" "F.Mask" "F.Paste")
			(net "GND")
		)
		(pad "16" smd rect
			(at -2.050034 -50.574956 90)
			(size 0.519938 1.4986)
			(layers "F.Cu" "F.Mask" "F.Paste")
			(net "M_L_CPU1_SA_DQ<5>")
		)
		(pad "17" smd rect
			(at -2.050034 -49.725072 90)
			(size 0.519938 1.4986)
			(layers "F.Cu" "F.Mask" "F.Paste")
			(net "GND")
		)
		(pad "18" smd rect
			(at -2.050034 -48.874934 90)
			(size 0.519938 1.4986)
			(layers "F.Cu" "F.Mask" "F.Paste")
			(net "M_L_CPU1_SA_DQ<8>")
		)
		(pad "19" smd rect
			(at -2.050034 -48.02505 90)
			(size 0.519938 1.4986)
			(layers "F.Cu" "F.Mask" "F.Paste")
			(net "GND")
		)
		(pad "20" smd rect
			(at -2.050034 -47.174912 90)
			(size 0.519938 1.4986)
			(layers "F.Cu" "F.Mask" "F.Paste")
			(net "M_L_CPU1_SA_DQ<9>")
		)
		(pad "21" smd rect
			(at -2.050034 -46.325028 90)
			(size 0.519938 1.4986)
			(layers "F.Cu" "F.Mask" "F.Paste")
			(net "GND")
		)
		(pad "22" smd rect
			(at -2.050034 -45.47489 90)
			(size 0.519938 1.4986)
			(layers "F.Cu" "F.Mask" "F.Paste")
			(net "M_L_CPU1_SA_DQS_DP<1>")
		)
		(pad "23" smd rect
			(at -2.050034 -44.625006 90)
			(size 0.519938 1.4986)
			(layers "F.Cu" "F.Mask" "F.Paste")
			(net "M_L_CPU1_SA_DQS_DN<1>")
		)
		(pad "24" smd rect
			(at -2.050034 -43.775122 90)
			(size 0.519938 1.4986)
			(layers "F.Cu" "F.Mask" "F.Paste")
			(net "GND")
		)
		(pad "25" smd rect
			(at -2.050034 -42.924984 90)
			(size 0.519938 1.4986)
			(layers "F.Cu" "F.Mask" "F.Paste")
			(net "M_L_CPU1_SA_DQ<12>")
		)
		(pad "26" smd rect
			(at -2.050034 -42.0751 90)
			(size 0.519938 1.4986)
			(layers "F.Cu" "F.Mask" "F.Paste")
			(net "GND")
		)
		(pad "27" smd rect
			(at -2.050034 -41.224962 90)
			(size 0.519938 1.4986)
			(layers "F.Cu" "F.Mask" "F.Paste")
			(net "M_L_CPU1_SA_DQ<13>")
		)
		(pad "28" smd rect
			(at -2.050034 -40.375078 90)
			(size 0.519938 1.4986)
			(layers "F.Cu" "F.Mask" "F.Paste")
			(net "GND")
		)
		(pad "29" smd rect
			(at -2.050034 -39.52494 90)
			(size 0.519938 1.4986)
			(layers "F.Cu" "F.Mask" "F.Paste")
			(net "M_L_CPU1_SA_DQ<16>")
		)
		(pad "30" smd rect
			(at -2.050034 -38.675056 90)
			(size 0.519938 1.4986)
			(layers "F.Cu" "F.Mask" "F.Paste")
			(net "GND")
		)
		(pad "31" smd rect
			(at -2.050034 -37.824918 90)
			(size 0.519938 1.4986)
			(layers "F.Cu" "F.Mask" "F.Paste")
			(net "M_L_CPU1_SA_DQ<17>")
		)
		(pad "32" smd rect
			(at -2.050034 -36.975034 90)
			(size 0.519938 1.4986)
			(layers "F.Cu" "F.Mask" "F.Paste")
			(net "GND")
		)
		(pad "33" smd rect
			(at -2.050034 -36.124896 90)
			(size 0.519938 1.4986)
			(layers "F.Cu" "F.Mask" "F.Paste")
			(net "M_L_CPU1_SA_DQS_DP<2>")
		)
		(pad "34" smd rect
			(at -2.050034 -35.275012 90)
			(size 0.519938 1.4986)
			(layers "F.Cu" "F.Mask" "F.Paste")
			(net "M_L_CPU1_SA_DQS_DN<2>")
		)
		(pad "35" smd rect
			(at -2.050034 -34.425128 90)
			(size 0.519938 1.4986)
			(layers "F.Cu" "F.Mask" "F.Paste")
			(net "GND")
		)
		(pad "36" smd rect
			(at -2.050034 -33.57499 90)
			(size 0.519938 1.4986)
			(layers "F.Cu" "F.Mask" "F.Paste")
			(net "M_L_CPU1_SA_DQ<20>")
		)
		(pad "37" smd rect
			(at -2.050034 -32.725106 90)
			(size 0.519938 1.4986)
			(layers "F.Cu" "F.Mask" "F.Paste")
			(net "GND")
		)
		(pad "38" smd rect
			(at -2.050034 -31.874968 90)
			(size 0.519938 1.4986)
			(layers "F.Cu" "F.Mask" "F.Paste")
			(net "M_L_CPU1_SA_DQ<21>")
		)
		(pad "39" smd rect
			(at -2.050034 -31.025084 90)
			(size 0.519938 1.4986)
			(layers "F.Cu" "F.Mask" "F.Paste")
			(net "GND")
		)
		(pad "40" smd rect
			(at -2.050034 -30.174946 90)
			(size 0.519938 1.4986)
			(layers "F.Cu" "F.Mask" "F.Paste")
			(net "M_L_CPU1_SA_DQ<24>")
		)
		(pad "41" smd rect
			(at -2.050034 -29.325062 90)
			(size 0.519938 1.4986)
			(layers "F.Cu" "F.Mask" "F.Paste")
			(net "GND")
		)
		(pad "42" smd rect
			(at -2.050034 -28.474924 90)
			(size 0.519938 1.4986)
			(layers "F.Cu" "F.Mask" "F.Paste")
			(net "M_L_CPU1_SA_DQ<25>")
		)
		(pad "43" smd rect
			(at -2.050034 -27.62504 90)
			(size 0.519938 1.4986)
			(layers "F.Cu" "F.Mask" "F.Paste")
			(net "GND")
		)
		(pad "44" smd rect
			(at -2.050034 -26.774902 90)
			(size 0.519938 1.4986)
			(layers "F.Cu" "F.Mask" "F.Paste")
			(net "M_L_CPU1_SA_DQS_DP<3>")
		)
		(pad "45" smd rect
			(at -2.050034 -25.925018 90)
			(size 0.519938 1.4986)
			(layers "F.Cu" "F.Mask" "F.Paste")
			(net "M_L_CPU1_SA_DQS_DN<3>")
		)
		(pad "46" smd rect
			(at -2.050034 -25.07488 90)
			(size 0.519938 1.4986)
			(layers "F.Cu" "F.Mask" "F.Paste")
			(net "GND")
		)
	)
)
